(kicad_pcb
	(version 20260206)
	(generator "pcbnew")
	(generator_version "10.0")
	(general
		(thickness 1.6)
		(legacy_teardrops no)
	)
	(paper "A4")
	(title_block
		(title "Bryce Canyon_IOM_IOC_16318-2_OCP.brd")
		(comment 1 "Bryce Canyon / footprints 569-575 of 1605")
	)
	(layers
		(0 "F.Cu" signal "TOP")
		(4 "In1.Cu" signal "L2GND")
		(6 "In2.Cu" signal "L3")
		(8 "In3.Cu" signal "L4VCC")
		(10 "In4.Cu" signal "L5VCC")
		(12 "In5.Cu" signal "L6")
		(14 "In6.Cu" signal "L7GND")
		(2 "B.Cu" signal "BOTTOM")
		(9 "F.Adhes" user "F.Adhesive")
		(11 "B.Adhes" user "B.Adhesive")
		(13 "F.Paste" user "Package Geometry/Pastemask Top")
		(15 "B.Paste" user "Package Geometry/Pastemask Bottom")
		(5 "F.SilkS" user "Ref Des/Silkscreen Top")
		(7 "B.SilkS" user "Ref Des/Silkscreen Bottom")
		(1 "F.Mask" user "Board Geometry/Soldermask Top")
		(3 "B.Mask" user "Board Geometry/Soldermask Bottom")
		(17 "Dwgs.User" user "User.Drawings")
		(19 "Cmts.User" user "User.Comments")
		(21 "Eco1.User" user "User.Eco1")
		(23 "Eco2.User" user "User.Eco2")
		(25 "Edge.Cuts" user "Board Geometry/Outline")
		(27 "Margin" user)
		(31 "F.CrtYd" user "Package Geometry/Place Bound Top")
		(29 "B.CrtYd" user "Package Geometry/Place Bound Bottom")
		(35 "F.Fab" user "Ref Des/Assembly Top")
		(33 "B.Fab" user "Ref Des/Assembly Bottom")
	)
	(footprint ""
		(layer "F.Cu")
		(at 69.883782 -156.277818 180)
		(property "Reference" "X2"
			(at 0 0 180)
			(layer "F.SilkS")
			(hide yes)
			(effects
				(font
					(size 1.27 1.27)
				)
			)
		)
		(property "Value" "OSC-50MHZ-16-GP"
			(at 0.0127 -2.7686 180)
			(unlocked yes)
			(layer "F.Fab")
			(hide yes)
			(effects
				(font
					(size 1.016 1.016)
					(thickness 0.1524)
				)
			)
		)
		(property "Device Type" "OSC-3225-4P-3H48"
			(at 0.0127 -4.2926 180)
			(unlocked yes)
			(layer "F.Fab")
			(hide yes)
			(effects
				(font
					(size 1.016 1.016)
					(thickness 0.1524)
				)
			)
		)
		(duplicate_pad_numbers_are_jumpers no)
		(fp_line
			(start 2.1209 1.5367)
			(end -2.1209 1.5367)
			(stroke
				(width 0.1524)
				(type default)
			)
			(layer "F.SilkS")
		)
		(fp_line
			(start 2.1209 -1.5367)
			(end 2.1209 1.5367)
			(stroke
				(width 0.1524)
				(type default)
			)
			(layer "F.SilkS")
		)
		(fp_line
			(start -1.3208 1.6256)
			(end -2.2352 1.6256)
			(stroke
				(width 0.3302)
				(type default)
			)
			(layer "F.SilkS")
		)
		(fp_line
			(start -2.1209 1.5367)
			(end -2.1209 -1.5367)
			(stroke
				(width 0.1524)
				(type default)
			)
			(layer "F.SilkS")
		)
		(fp_line
			(start -2.1209 -1.5367)
			(end 2.1209 -1.5367)
			(stroke
				(width 0.1524)
				(type default)
			)
			(layer "F.SilkS")
		)
		(fp_line
			(start -2.2352 1.6256)
			(end -2.2352 0.635)
			(stroke
				(width 0.3302)
				(type default)
			)
			(layer "F.SilkS")
		)
		(fp_poly
			(pts
				(xy -2.8321 1.459992) (xy -2.8321 0.189992) (xy -2.1971 0.824992)
			)
			(stroke
				(width 0)
				(type default)
			)
			(fill yes)
			(layer "F.SilkS")
		)
		(fp_rect
			(start -1.6002 1.2446)
			(end 1.6002 -1.2446)
			(stroke
				(width 0)
				(type default)
			)
			(fill no)
			(layer "F.CrtYd")
		)
		(fp_poly
			(pts
				(xy -2.3749 1.7907) (xy -2.3749 -1.7907) (xy 2.3749 -1.7907) (xy 2.3749 1.7907) (xy 1.6002 1.7907)
				(xy 1.6002 -1.2446) (xy -1.6002 -1.2446) (xy -1.6002 1.2446) (xy 1.59512 1.2446) (xy 1.59512 1.7907)
			)
			(stroke
				(width 0)
				(type default)
			)
			(fill no)
			(layer "F.CrtYd")
		)
		(fp_rect
			(start -2.3749 1.7907)
			(end 2.3749 -1.7907)
			(stroke
				(width 0)
				(type default)
			)
			(fill no)
			(layer "F.Fab")
		)
		(pad "1" smd rect
			(at -1.171448 0.824992 180)
			(size 1.397 0.9144)
			(layers "F.Cu" "F.Mask" "F.Paste")
			(net "FM_OSC_50M_EN")
		)
		(pad "2" smd rect
			(at 1.171448 0.824992 180)
			(size 1.397 0.9144)
			(layers "F.Cu" "F.Mask" "F.Paste")
			(net "GND")
		)
		(pad "3" smd rect
			(at 1.171448 -0.824992 180)
			(size 1.397 0.9144)
			(layers "F.Cu" "F.Mask" "F.Paste")
			(net "50M_CLK_OUT")
		)
		(pad "4" smd rect
			(at -1.171448 -0.824992 180)
			(size 1.397 0.9144)
			(layers "F.Cu" "F.Mask" "F.Paste")
			(net "P3V3_STBY")
		)
		(zone
			(layer "F.Cu")
			(hatch none 0.5)
			(connect_pads
				(clearance 0)
			)
			(min_thickness 0.25)
			(keepout
				(tracks not_allowed)
				(vias allowed)
				(pads allowed)
				(copperpour not_allowed)
				(footprints allowed)
			)
			(placement
				(enabled no)
				(sheetname "")
			)
			(fill
				(thermal_gap 0.5)
				(thermal_bridge_width 0.5)
				(island_removal_mode 0)
			)
			(polygon
				(pts
					(xy 70.03161 -156.32049) (xy 69.735954 -156.32049) (xy 69.735954 -156.235146) (xy 70.03161 -156.235146)
				)
			)
		)
		(zone
			(layer "F.Cu")
			(hatch none 0.5)
			(connect_pads
				(clearance 0)
			)
			(min_thickness 0.25)
			(keepout
				(tracks allowed)
				(vias not_allowed)
				(pads allowed)
				(copperpour not_allowed)
				(footprints allowed)
			)
			(placement
				(enabled no)
				(sheetname "")
			)
			(fill
				(thermal_gap 0.5)
				(thermal_bridge_width 0.5)
				(island_removal_mode 0)
			)
			(polygon
				(pts
					(xy 70.35673 -157.56001) (xy 70.35673 -156.64561) (xy 71.75373 -156.64561) (xy 71.75373 -155.910026)
					(xy 70.35673 -155.910026) (xy 70.35673 -154.995626) (xy 69.410834 -154.995626) (xy 69.410834 -155.910026)
					(xy 68.013834 -155.910026) (xy 68.013834 -156.64561) (xy 69.410834 -156.64561) (xy 69.410834 -157.56001)
				)
			)
		)
	)
	(footprint ""
		(layer "F.Cu")
		(at 12.500102 -187.999878)
		(property "Reference" ""
			(at 0 0 0)
			(layer "F.SilkS")
			(hide yes)
			(effects
				(font
					(size 1.27 1.27)
				)
			)
		)
		(property "Value" "*"
			(at 6.2484 0.3429 0)
			(unlocked yes)
			(layer "F.Fab")
			(hide yes)
			(effects
				(font
					(size 1.016 1.016)
					(thickness 0.1524)
				)
			)
		)
		(duplicate_pad_numbers_are_jumpers no)
		(fp_poly
			(pts
				(arc
					(start 5.0673 0)
					(mid -5.0673 0)
					(end 5.0673 0)
				)
			)
			(stroke
				(width 0)
				(type default)
			)
			(fill no)
			(layer "B.CrtYd")
		)
		(fp_poly
			(pts
				(arc
					(start 5.0673 0)
					(mid -5.0673 0)
					(end 5.0673 0)
				)
			)
			(stroke
				(width 0)
				(type default)
			)
			(fill no)
			(layer "F.CrtYd")
		)
		(fp_poly
			(pts
				(arc
					(start 5.0673 0)
					(mid -5.0673 0)
					(end 5.0673 0)
				)
			)
			(stroke
				(width 0)
				(type default)
			)
			(fill no)
			(layer "B.Fab")
		)
		(fp_poly
			(pts
				(arc
					(start 5.0673 0)
					(mid -5.0673 0)
					(end 5.0673 0)
				)
			)
			(stroke
				(width 0)
				(type default)
			)
			(fill no)
			(layer "F.Fab")
		)
		(pad "1" thru_hole circle
			(at 0 0)
			(size 9.525 9.525)
			(drill 4.0132)
			(layers "*.Cu" "*.Mask")
			(remove_unused_layers no)
			(net "Net_72")
			(clearance -2.2479)
			(thermal_gap 0.3048)
			(padstack
				(mode front_inner_back)
				(layer "Inner"
					(shape circle)
					(size 4.4196 4.4196)
					(clearance 0.3048)
				)
				(layer "B.Cu"
					(shape circle)
					(size 9.525 9.525)
					(clearance -2.2479)
				)
			)
		)
	)
	(footprint ""
		(layer "F.Cu")
		(at 178.0794 -38.5064)
		(property "Reference" "TP177"
			(at 0 0 0)
			(layer "F.SilkS")
			(hide yes)
			(effects
				(font
					(size 1.27 1.27)
				)
			)
		)
		(property "Value" "TPAD28-2-GP"
			(at -0.0127 -1.6637 0)
			(unlocked yes)
			(layer "F.Fab")
			(hide yes)
			(effects
				(font
					(size 1.016 1.016)
					(thickness 0.1524)
				)
			)
		)
		(property "Device Type" "TPAD28"
			(at -0.0127 -3.1877 0)
			(unlocked yes)
			(layer "F.Fab")
			(hide yes)
			(effects
				(font
					(size 1.016 1.016)
					(thickness 0.1524)
				)
			)
		)
		(duplicate_pad_numbers_are_jumpers no)
		(fp_poly
			(pts
				(arc
					(start 0.3556 0)
					(mid -0.3556 0)
					(end 0.3556 0)
				)
			)
			(stroke
				(width 0)
				(type default)
			)
			(fill no)
			(layer "F.CrtYd")
		)
		(fp_poly
			(pts
				(arc
					(start 0.6096 0)
					(mid -0.6096 0)
					(end 0.6096 0)
				)
			)
			(stroke
				(width 0)
				(type default)
			)
			(fill no)
			(layer "F.Fab")
		)
		(pad "1" smd circle
			(at 0 0)
			(size 0.7112 0.7112)
			(layers "F.Cu" "F.Mask" "F.Paste")
			(net "ZDEF_EXTA_TP_D2")
		)
	)
	(footprint ""
		(layer "F.Cu")
		(at 57.484264 -167.377618 90)
		(property "Reference" "R197"
			(at 0 0 90)
			(layer "F.SilkS")
			(hide yes)
			(effects
				(font
					(size 1.27 1.27)
				)
			)
		)
		(property "Value" "2K2R2F-GP"
			(at 0.064008 -3.993896 90)
			(unlocked yes)
			(layer "F.Fab")
			(hide yes)
			(effects
				(font
					(size 1.016 1.016)
					(thickness 0.1524)
				)
			)
		)
		(property "Device Type" "R402H16"
			(at 0.064008 -5.517896 90)
			(unlocked yes)
			(layer "F.Fab")
			(hide yes)
			(effects
				(font
					(size 1.016 1.016)
					(thickness 0.1524)
				)
			)
		)
		(duplicate_pad_numbers_are_jumpers no)
		(fp_line
			(start 0.508 -0.9398)
			(end -0.508 -0.9398)
			(stroke
				(width 0.1524)
				(type default)
			)
			(layer "F.SilkS")
		)
		(fp_line
			(start -0.508 -0.9398)
			(end -0.508 0.9398)
			(stroke
				(width 0.1524)
				(type default)
			)
			(layer "F.SilkS")
		)
		(fp_rect
			(start -0.508 0.9398)
			(end 0.508 -0.9398)
			(stroke
				(width 0)
				(type default)
			)
			(fill no)
			(layer "F.CrtYd")
		)
		(fp_rect
			(start -0.508 0.9398)
			(end 0.508 -0.9398)
			(stroke
				(width 0)
				(type default)
			)
			(fill no)
			(layer "F.Fab")
		)
		(pad "1" smd custom
			(at 0 -0.4445 90)
			(size 0.1397 0.1397)
			(layers "F.Cu" "F.Mask" "F.Paste")
			(net "I2C_TPM_SDA")
			(options
				(clearance outline)
				(anchor circle)
			)
			(primitives
				(gr_poly
					(pts
						(arc
							(start -0.1778 -0.2794)
							(mid -0.249642 -0.249642)
							(end -0.2794 -0.1778)
						)
						(arc
							(start -0.2794 0.1778)
							(mid -0.249642 0.249642)
							(end -0.1778 0.2794)
						)
						(arc
							(start 0.1778 0.2794)
							(mid 0.249642 0.249642)
							(end 0.2794 0.1778)
						)
						(arc
							(start 0.2794 -0.1778)
							(mid 0.249642 -0.249642)
							(end 0.1778 -0.2794)
						)
					)
					(width 0)
					(fill yes)
				)
			)
		)
		(pad "2" smd custom
			(at 0 0.4445 90)
			(size 0.1397 0.1397)
			(layers "F.Cu" "F.Mask" "F.Paste")
			(net "P3V3_STBY")
			(options
				(clearance outline)
				(anchor circle)
			)
			(primitives
				(gr_poly
					(pts
						(arc
							(start -0.1778 -0.2794)
							(mid -0.249642 -0.249642)
							(end -0.2794 -0.1778)
						)
						(arc
							(start -0.2794 0.1778)
							(mid -0.249642 0.249642)
							(end -0.1778 0.2794)
						)
						(arc
							(start 0.1778 0.2794)
							(mid 0.249642 0.249642)
							(end 0.2794 0.1778)
						)
						(arc
							(start 0.2794 -0.1778)
							(mid 0.249642 -0.249642)
							(end 0.1778 -0.2794)
						)
					)
					(width 0)
					(fill yes)
				)
			)
		)
	)
	(footprint ""
		(layer "F.Cu")
		(at 177.2412 -52.7304 -90)
		(property "Reference" "R674"
			(at 0 0 270)
			(layer "F.SilkS")
			(hide yes)
			(effects
				(font
					(size 1.27 1.27)
				)
			)
		)
		(property "Value" "10KR2F-2-GP"
			(at 0.064008 -3.993896 270)
			(unlocked yes)
			(layer "F.Fab")
			(hide yes)
			(effects
				(font
					(size 1.016 1.016)
					(thickness 0.1524)
				)
			)
		)
		(property "Device Type" "R402H16"
			(at 0.064008 -5.517896 270)
			(unlocked yes)
			(layer "F.Fab")
			(hide yes)
			(effects
				(font
					(size 1.016 1.016)
					(thickness 0.1524)
				)
			)
		)
		(duplicate_pad_numbers_are_jumpers no)
		(fp_line
			(start -0.508 -0.9398)
			(end -0.508 0.9398)
			(stroke
				(width 0.1524)
				(type default)
			)
			(layer "F.SilkS")
		)
		(fp_line
			(start 0.508 -0.9398)
			(end -0.508 -0.9398)
			(stroke
				(width 0.1524)
				(type default)
			)
			(layer "F.SilkS")
		)
		(fp_rect
			(start -0.508 0.9398)
			(end 0.508 -0.9398)
			(stroke
				(width 0)
				(type default)
			)
			(fill no)
			(layer "F.CrtYd")
		)
		(fp_rect
			(start -0.508 0.9398)
			(end 0.508 -0.9398)
			(stroke
				(width 0)
				(type default)
			)
			(fill no)
			(layer "F.Fab")
		)
		(pad "1" smd custom
			(at 0 -0.4445 270)
			(size 0.1397 0.1397)
			(layers "F.Cu" "F.Mask" "F.Paste")
			(net "XM_ADDR_11")
			(options
				(clearance outline)
				(anchor circle)
			)
			(primitives
				(gr_poly
					(pts
						(arc
							(start -0.1778 -0.2794)
							(mid -0.249642 -0.249642)
							(end -0.2794 -0.1778)
						)
						(arc
							(start -0.2794 0.1778)
							(mid -0.249642 0.249642)
							(end -0.1778 0.2794)
						)
						(arc
							(start 0.1778 0.2794)
							(mid 0.249642 0.249642)
							(end 0.2794 0.1778)
						)
						(arc
							(start 0.2794 -0.1778)
							(mid 0.249642 -0.249642)
							(end 0.1778 -0.2794)
						)
					)
					(width 0)
					(fill yes)
				)
			)
		)
		(pad "2" smd custom
			(at 0 0.4445 270)
			(size 0.1397 0.1397)
			(layers "F.Cu" "F.Mask" "F.Paste")
			(net "GND")
			(options
				(clearance outline)
				(anchor circle)
			)
			(primitives
				(gr_poly
					(pts
						(arc
							(start -0.1778 -0.2794)
							(mid -0.249642 -0.249642)
							(end -0.2794 -0.1778)
						)
						(arc
							(start -0.2794 0.1778)
							(mid -0.249642 0.249642)
							(end -0.1778 0.2794)
						)
						(arc
							(start 0.1778 0.2794)
							(mid 0.249642 0.249642)
							(end 0.2794 0.1778)
						)
						(arc
							(start 0.2794 -0.1778)
							(mid 0.249642 -0.249642)
							(end 0.1778 -0.2794)
						)
					)
					(width 0)
					(fill yes)
				)
			)
		)
	)
	(footprint ""
		(layer "F.Cu")
		(at 98.928174 -158.441644 90)
		(property "Reference" "R26"
			(at 0 0 90)
			(layer "F.SilkS")
			(hide yes)
			(effects
				(font
					(size 1.27 1.27)
				)
			)
		)
		(property "Value" "0R2J-2-GP"
			(at 0.064008 -3.993896 90)
			(unlocked yes)
			(layer "F.Fab")
			(hide yes)
			(effects
				(font
					(size 1.016 1.016)
					(thickness 0.1524)
				)
			)
		)
		(property "Device Type" "R402H16"
			(at 0.064008 -5.517896 90)
			(unlocked yes)
			(layer "F.Fab")
			(hide yes)
			(effects
				(font
					(size 1.016 1.016)
					(thickness 0.1524)
				)
			)
		)
		(duplicate_pad_numbers_are_jumpers no)
		(fp_line
			(start 0.508 -0.9398)
			(end -0.508 -0.9398)
			(stroke
				(width 0.1524)
				(type default)
			)
			(layer "F.SilkS")
		)
		(fp_line
			(start -0.508 -0.9398)
			(end -0.508 0.9398)
			(stroke
				(width 0.1524)
				(type default)
			)
			(layer "F.SilkS")
		)
		(fp_rect
			(start -0.508 0.9398)
			(end 0.508 -0.9398)
			(stroke
				(width 0)
				(type default)
			)
			(fill no)
			(layer "F.CrtYd")
		)
		(fp_rect
			(start -0.508 0.9398)
			(end 0.508 -0.9398)
			(stroke
				(width 0)
				(type default)
			)
			(fill no)
			(layer "F.Fab")
		)
		(pad "1" smd custom
			(at 0 -0.4445 90)
			(size 0.1397 0.1397)
			(layers "F.Cu" "F.Mask" "F.Paste")
			(net "USB_RESET_N")
			(options
				(clearance outline)
				(anchor circle)
			)
			(primitives
				(gr_poly
					(pts
						(arc
							(start -0.1778 -0.2794)
							(mid -0.249642 -0.249642)
							(end -0.2794 -0.1778)
						)
						(arc
							(start -0.2794 0.1778)
							(mid -0.249642 0.249642)
							(end -0.1778 0.2794)
						)
						(arc
							(start 0.1778 0.2794)
							(mid 0.249642 0.249642)
							(end 0.2794 0.1778)
						)
						(arc
							(start 0.2794 -0.1778)
							(mid 0.249642 -0.249642)
							(end 0.1778 -0.2794)
						)
					)
					(width 0)
					(fill yes)
				)
			)
		)
		(pad "2" smd custom
			(at 0 0.4445 90)
			(size 0.1397 0.1397)
			(layers "F.Cu" "F.Mask" "F.Paste")
			(net "PCIE_COMP_TO_IOM_RST_4")
			(options
				(clearance outline)
				(anchor circle)
			)
			(primitives
				(gr_poly
					(pts
						(arc
							(start -0.1778 -0.2794)
							(mid -0.249642 -0.249642)
							(end -0.2794 -0.1778)
						)
						(arc
							(start -0.2794 0.1778)
							(mid -0.249642 0.249642)
							(end -0.1778 0.2794)
						)
						(arc
							(start 0.1778 0.2794)
							(mid 0.249642 0.249642)
							(end 0.2794 0.1778)
						)
						(arc
							(start 0.2794 -0.1778)
							(mid 0.249642 -0.249642)
							(end 0.1778 -0.2794)
						)
					)
					(width 0)
					(fill yes)
				)
			)
		)
	)
	(footprint ""
		(layer "F.Cu")
		(at 74.9554 -145.7198 90)
		(property "Reference" "R329"
			(at 0 0 90)
			(layer "F.SilkS")
			(hide yes)
			(effects
				(font
					(size 1.27 1.27)
				)
			)
		)
		(property "Value" "0R2J-2-GP"
			(at 0.064008 -3.993896 90)
			(unlocked yes)
			(layer "F.Fab")
			(hide yes)
			(effects
				(font
					(size 1.016 1.016)
					(thickness 0.1524)
				)
			)
		)
		(property "Device Type" "R402H16"
			(at 0.064008 -5.517896 90)
			(unlocked yes)
			(layer "F.Fab")
			(hide yes)
			(effects
				(font
					(size 1.016 1.016)
					(thickness 0.1524)
				)
			)
		)
		(duplicate_pad_numbers_are_jumpers no)
		(fp_line
			(start 0.508 -0.9398)
			(end -0.508 -0.9398)
			(stroke
				(width 0.1524)
				(type default)
			)
			(layer "F.SilkS")
		)
		(fp_line
			(start -0.508 -0.9398)
			(end -0.508 0.9398)
			(stroke
				(width 0.1524)
				(type default)
			)
			(layer "F.SilkS")
		)
		(fp_rect
			(start -0.508 0.9398)
			(end 0.508 -0.9398)
			(stroke
				(width 0)
				(type default)
			)
			(fill no)
			(layer "F.CrtYd")
		)
		(fp_rect
			(start -0.508 0.9398)
			(end 0.508 -0.9398)
			(stroke
				(width 0)
				(type default)
			)
			(fill no)
			(layer "F.Fab")
		)
		(pad "1" smd custom
			(at 0 -0.4445 90)
			(size 0.1397 0.1397)
			(layers "F.Cu" "F.Mask" "F.Paste")
			(net "I2C_DPB_SCL")
			(options
				(clearance outline)
				(anchor circle)
			)
			(primitives
				(gr_poly
					(pts
						(arc
							(start -0.1778 -0.2794)
							(mid -0.249642 -0.249642)
							(end -0.2794 -0.1778)
						)
						(arc
							(start -0.2794 0.1778)
							(mid -0.249642 0.249642)
							(end -0.1778 0.2794)
						)
						(arc
							(start 0.1778 0.2794)
							(mid 0.249642 0.249642)
							(end 0.2794 0.1778)
						)
						(arc
							(start 0.2794 -0.1778)
							(mid 0.249642 -0.249642)
							(end 0.1778 -0.2794)
						)
					)
					(width 0)
					(fill yes)
				)
			)
		)
		(pad "2" smd custom
			(at 0 0.4445 90)
			(size 0.1397 0.1397)
			(layers "F.Cu" "F.Mask" "F.Paste")
			(net "I2C_DPB_SCL_R")
			(options
				(clearance outline)
				(anchor circle)
			)
			(primitives
				(gr_poly
					(pts
						(arc
							(start -0.1778 -0.2794)
							(mid -0.249642 -0.249642)
							(end -0.2794 -0.1778)
						)
						(arc
							(start -0.2794 0.1778)
							(mid -0.249642 0.249642)
							(end -0.1778 0.2794)
						)
						(arc
							(start 0.1778 0.2794)
							(mid 0.249642 0.249642)
							(end 0.2794 0.1778)
						)
						(arc
							(start 0.2794 -0.1778)
							(mid 0.249642 -0.249642)
							(end 0.1778 -0.2794)
						)
					)
					(width 0)
					(fill yes)
				)
			)
		)
	)
)
